# S9S_MB_2U (Grand Teton) — schematic netlist excerpt (pin names and nets, part order shuffled) for the footprints in the layout excerpt that follows; sources: Cadence DE-HDL packaged netlist, KiCad conversion of 03242023_DA0F0TMBIJ0_F0T_Motherboard_J_brd_V01_OCP.brd

Q144  MOSFET_NCH_DUAL  PJT138K IC  pkg SOT363XD  page 224
  S1  = GND
  G1  = PWRGD_PS_PWROK_PLD
  D2  = PWRGD_PS_PWROK_PLD_ISO
  S2  = GND
  G2  = PWRGD_PS_PWROK_PLD_N
  D1  = PWRGD_PS_PWROK_PLD_N

R2908  Q_RES  5.11K 1% CHIP  pkg 0402LF  page 250 : A = P3V3 ; B = P3V3_ADC

(kicad_pcb
	(version 20260206)
	(generator "pcbnew")
	(generator_version "10.0")
	(general
		(thickness 1.6)
		(legacy_teardrops no)
	)
	(paper "A4")
	(title_block
		(title "03242023_DA0F0TMBIJ0_F0T_Motherboard_J_brd_V01_OCP.brd")
		(comment 1 "Grand Teton / footprints 1136-1137 of 6105")
	)
	(layers
		(0 "F.Cu" signal "TOP")
		(4 "In1.Cu" signal "GND")
		(6 "In2.Cu" signal "IN1")
		(8 "In3.Cu" signal "GND1")
		(10 "In4.Cu" signal "IN2")
		(12 "In5.Cu" signal "GND2")
		(14 "In6.Cu" signal "IN3")
		(16 "In7.Cu" signal "GND3")
		(18 "In8.Cu" signal "VCC")
		(20 "In9.Cu" signal "VCC1")
		(22 "In10.Cu" signal "GND4")
		(24 "In11.Cu" signal "IN4")
		(26 "In12.Cu" signal "GND5")
		(28 "In13.Cu" signal "IN5")
		(30 "In14.Cu" signal "GND6")
		(32 "In15.Cu" signal "IN6")
		(34 "In16.Cu" signal "GND7")
		(2 "B.Cu" signal "BOTTOM")
		(9 "F.Adhes" user "F.Adhesive")
		(11 "B.Adhes" user "B.Adhesive")
		(13 "F.Paste" user "Package Geometry/Pastemask Top")
		(15 "B.Paste" user "Package Geometry/Pastemask Bottom")
		(5 "F.SilkS" user "Ref Des/Silkscreen Top")
		(7 "B.SilkS" user "Ref Des/Silkscreen Bottom")
		(1 "F.Mask" user "Board Geometry/Soldermask Top")
		(3 "B.Mask" user "Board Geometry/Soldermask Bottom")
		(17 "Dwgs.User" user "User.Drawings")
		(19 "Cmts.User" user "User.Comments")
		(21 "Eco1.User" user "User.Eco1")
		(23 "Eco2.User" user "User.Eco2")
		(25 "Edge.Cuts" user "Board Geometry/Outline")
		(27 "Margin" user)
		(31 "F.CrtYd" user "Package Geometry/Place Bound Top")
		(29 "B.CrtYd" user "Package Geometry/Place Bound Bottom")
		(35 "F.Fab" user "Ref Des/Assembly Top")
		(33 "B.Fab" user "Ref Des/Assembly Bottom")
	)
	(footprint ""
		(layer "F.Cu")
		(at 149.987 -131.282948 180)
		(property "Reference" "Q144"
			(at 1.15824 -2.07391 0)
			(unlocked yes)
			(layer "F.SilkS")
			(effects
				(font
					(size 0.7874 0.5842)
					(thickness 0.1524)
				)
				(justify left)
			)
		)
		(property "Value" ""
			(at 0 0 180)
			(layer "F.Fab")
			(effects
				(font
					(size 1.27 1.27)
				)
			)
		)
		(duplicate_pad_numbers_are_jumpers no)
		(fp_line
			(start 1.332738 1.100074)
			(end -1.332738 1.100074)
			(stroke
				(width 0.1524)
				(type default)
			)
			(layer "F.SilkS")
		)
		(fp_line
			(start 1.332738 -1.100074)
			(end 1.332738 1.100074)
			(stroke
				(width 0.1524)
				(type default)
			)
			(layer "F.SilkS")
		)
		(fp_line
			(start 0.4826 -1.100074)
			(end 1.332738 -1.100074)
			(stroke
				(width 0.1524)
				(type default)
			)
			(layer "F.SilkS")
		)
		(fp_line
			(start 0 -0.541274)
			(end 0.4826 -1.100074)
			(stroke
				(width 0.1524)
				(type default)
			)
			(layer "F.SilkS")
		)
		(fp_line
			(start -0.4826 -1.100074)
			(end 0 -0.541274)
			(stroke
				(width 0.1524)
				(type default)
			)
			(layer "F.SilkS")
		)
		(fp_line
			(start -1.332738 1.100074)
			(end -1.332738 -1.100074)
			(stroke
				(width 0.1524)
				(type default)
			)
			(layer "F.SilkS")
		)
		(fp_line
			(start -1.332738 -1.100074)
			(end -0.4826 -1.100074)
			(stroke
				(width 0.1524)
				(type default)
			)
			(layer "F.SilkS")
		)
		(fp_poly
			(pts
				(xy -2.05486 -0.910844) (xy -1.533144 -0.649986) (xy -2.05486 -0.389128)
			)
			(stroke
				(width 0)
				(type default)
			)
			(fill yes)
			(layer "F.SilkS")
		)
		(fp_line
			(start 0.674878 1.100074)
			(end -0.674878 1.100074)
			(stroke
				(width 0.1)
				(type default)
			)
			(layer "F.Fab")
		)
		(fp_line
			(start 0.674878 -1.100074)
			(end 0.674878 1.100074)
			(stroke
				(width 0.1)
				(type default)
			)
			(layer "F.Fab")
		)
		(fp_line
			(start -0.674878 1.100074)
			(end -0.674878 -1.100074)
			(stroke
				(width 0.1)
				(type default)
			)
			(layer "F.Fab")
		)
		(fp_line
			(start -0.674878 -1.100074)
			(end 0.674878 -1.100074)
			(stroke
				(width 0.1)
				(type default)
			)
			(layer "F.Fab")
		)
		(fp_poly
			(pts
				(xy -2.2352 -0.298958) (xy -2.2352 -1.001014) (xy -1.533144 -0.649986)
			)
			(stroke
				(width 0)
				(type default)
			)
			(fill yes)
			(layer "F.Fab")
		)
		(pad "1" smd rect
			(at -0.94996 -0.649986 270)
			(size 0.4318 0.508)
			(layers "F.Cu" "F.Mask" "F.Paste")
			(net "GND")
		)
		(pad "2" smd rect
			(at -0.94996 0 270)
			(size 0.4318 0.508)
			(layers "F.Cu" "F.Mask" "F.Paste")
			(net "PWRGD_PS_PWROK_PLD")
		)
		(pad "3" smd rect
			(at -0.94996 0.649986 270)
			(size 0.4318 0.508)
			(layers "F.Cu" "F.Mask" "F.Paste")
			(net "PWRGD_PS_PWROK_PLD_ISO")
		)
		(pad "4" smd rect
			(at 0.94996 0.649986 270)
			(size 0.4318 0.508)
			(layers "F.Cu" "F.Mask" "F.Paste")
			(net "GND")
		)
		(pad "5" smd rect
			(at 0.94996 0 270)
			(size 0.4318 0.508)
			(layers "F.Cu" "F.Mask" "F.Paste")
			(net "PWRGD_PS_PWROK_PLD_N")
		)
		(pad "6" smd rect
			(at 0.94996 -0.649986 270)
			(size 0.4318 0.508)
			(layers "F.Cu" "F.Mask" "F.Paste")
			(net "PWRGD_PS_PWROK_PLD_N")
		)
	)
	(footprint ""
		(layer "F.Cu")
		(at 46.582584 -108.047282 180)
		(property "Reference" "R2908"
			(at 0 0 180)
			(layer "F.SilkS")
			(hide yes)
			(effects
				(font
					(size 1.27 1.27)
				)
			)
		)
		(property "Value" ""
			(at 0 0 180)
			(layer "F.Fab")
			(effects
				(font
					(size 1.27 1.27)
				)
			)
		)
		(duplicate_pad_numbers_are_jumpers no)
		(fp_line
			(start 0.7874 0.4064)
			(end -0.7874 0.4064)
			(stroke
				(width 0.1524)
				(type default)
			)
			(layer "F.SilkS")
		)
		(fp_line
			(start 0.7874 -0.4064)
			(end 0.7874 0.4064)
			(stroke
				(width 0.1524)
				(type default)
			)
			(layer "F.SilkS")
		)
		(fp_line
			(start -0.7874 0.4064)
			(end -0.7874 -0.4064)
			(stroke
				(width 0.1524)
				(type default)
			)
			(layer "F.SilkS")
		)
		(fp_line
			(start -0.7874 -0.4064)
			(end 0.7874 -0.4064)
			(stroke
				(width 0.1524)
				(type default)
			)
			(layer "F.SilkS")
		)
		(fp_line
			(start 0.67945 0.3048)
			(end 0.120396 0.3048)
			(stroke
				(width 0.1)
				(type default)
			)
			(layer "F.Fab")
		)
		(fp_line
			(start 0.67945 -0.3048)
			(end 0.67945 0.3048)
			(stroke
				(width 0.1)
				(type default)
			)
			(layer "F.Fab")
		)
		(fp_line
			(start 0.12065 -0.2794)
			(end 0.12065 -0.3048)
			(stroke
				(width 0.1)
				(type default)
			)
			(layer "F.Fab")
		)
		(fp_line
			(start 0.12065 -0.3048)
			(end 0.67945 -0.3048)
			(stroke
				(width 0.1)
				(type default)
			)
			(layer "F.Fab")
		)
		(fp_line
			(start 0.120396 0.3048)
			(end 0.120396 0.2794)
			(stroke
				(width 0.1)
				(type default)
			)
			(layer "F.Fab")
		)
		(fp_line
			(start 0.120396 0.2794)
			(end -0.12065 0.2794)
			(stroke
				(width 0.1)
				(type default)
			)
			(layer "F.Fab")
		)
		(fp_line
			(start -0.12065 0.3048)
			(end -0.67945 0.3048)
			(stroke
				(width 0.1)
				(type default)
			)
			(layer "F.Fab")
		)
		(fp_line
			(start -0.12065 0.2794)
			(end -0.12065 0.3048)
			(stroke
				(width 0.1)
				(type default)
			)
			(layer "F.Fab")
		)
		(fp_line
			(start -0.12065 -0.2794)
			(end 0.12065 -0.2794)
			(stroke
				(width 0.1)
				(type default)
			)
			(layer "F.Fab")
		)
		(fp_line
			(start -0.12065 -0.305054)
			(end -0.12065 -0.2794)
			(stroke
				(width 0.1)
				(type default)
			)
			(layer "F.Fab")
		)
		(fp_line
			(start -0.67945 0.3048)
			(end -0.67945 -0.305054)
			(stroke
				(width 0.1)
				(type default)
			)
			(layer "F.Fab")
		)
		(fp_line
			(start -0.67945 -0.305054)
			(end -0.12065 -0.305054)
			(stroke
				(width 0.1)
				(type default)
			)
			(layer "F.Fab")
		)
		(pad "1" smd circle
			(at -0.40005 0 180)
			(size 0 0)
			(layers "F.Cu" "F.Mask" "F.Paste")
			(net "P3V3")
		)
		(pad "2" smd circle
			(at 0.40005 0 180)
			(size 0 0)
			(layers "F.Cu" "F.Mask" "F.Paste")
			(net "P3V3_ADC")
		)
	)
)
